# BASEBOARD_FAB2 (Tioga Pass) — schematic netlist excerpt (pin names and nets, part order shuffled) for the footprints in the layout excerpt that follows; sources: Cadence DE-HDL packaged netlist, KiCad conversion of Wiwynn_Tioga_Pass_MB.brd

C7L6  CAP  10UF 4V 20% X6S  pkg 0603LF  page 234 : A = PVPP_KLM ; B = GND
C8W1  SC1U16V3KX-2GP  10%  pkg SMD-BCG  page 249 : \1\ = BMC_SELF_HW_D_RST ; \2\ = BMC_TPM_HW_C_RST
R1R5  RES  4.75K 1% CHIP  pkg 0402  page 170 : A = P3V3_STBY ; B = FM_FAST_PROCHOT_THROTTLE_DLY_BU

(kicad_pcb
	(version 20260206)
	(generator "pcbnew")
	(generator_version "10.0")
	(general
		(thickness 1.6)
		(legacy_teardrops no)
	)
	(paper "A4")
	(title_block
		(title "Wiwynn_Tioga_Pass_MB.brd")
		(comment 1 "Tioga Pass / footprints 3670-3672 of 4770")
	)
	(layers
		(0 "F.Cu" signal "TOP")
		(4 "In1.Cu" signal "L2GND")
		(6 "In2.Cu" signal "L3")
		(8 "In3.Cu" signal "L4GND")
		(10 "In4.Cu" signal "L5")
		(12 "In5.Cu" signal "L6GND")
		(14 "In6.Cu" signal "L7VCC")
		(16 "In7.Cu" signal "L8VCC")
		(18 "In8.Cu" signal "L9GND")
		(20 "In9.Cu" signal "L10")
		(22 "In10.Cu" signal "L11GND")
		(24 "In11.Cu" signal "L12")
		(26 "In12.Cu" signal "L13GND")
		(2 "B.Cu" signal "BOTTOM")
		(9 "F.Adhes" user "F.Adhesive")
		(11 "B.Adhes" user "B.Adhesive")
		(13 "F.Paste" user "Package Geometry/Pastemask Top")
		(15 "B.Paste" user "Package Geometry/Pastemask Bottom")
		(5 "F.SilkS" user "Ref Des/Silkscreen Top")
		(7 "B.SilkS" user "Ref Des/Silkscreen Bottom")
		(1 "F.Mask" user "Board Geometry/Soldermask Top")
		(3 "B.Mask" user "Board Geometry/Soldermask Bottom")
		(17 "Dwgs.User" user "User.Drawings")
		(19 "Cmts.User" user "User.Comments")
		(21 "Eco1.User" user "User.Eco1")
		(23 "Eco2.User" user "User.Eco2")
		(25 "Edge.Cuts" user "Board Geometry/Outline")
		(27 "Margin" user)
		(31 "F.CrtYd" user "Package Geometry/Place Bound Top")
		(29 "B.CrtYd" user "Package Geometry/Place Bound Bottom")
		(35 "F.Fab" user "Ref Des/Assembly Top")
		(33 "B.Fab" user "Ref Des/Assembly Bottom")
	)
	(footprint ""
		(layer "B.Cu")
		(at 452.857362 -17.749266 -90)
		(property "Reference" "C8W1"
			(at 0 0 90)
			(layer "B.SilkS")
			(hide yes)
			(effects
				(font
					(size 1.27 1.27)
				)
				(justify mirror)
			)
		)
		(property "Value" "*"
			(at 0 -2.9337 270)
			(unlocked yes)
			(layer "B.Fab")
			(hide yes)
			(effects
				(font
					(size 1.27 1.016)
					(thickness 0.1524)
				)
				(justify mirror)
			)
		)
		(property "Device Type" "SC1U16V3KX-2GP_SMD-BCG-SC1U16VA"
			(at 0 -4.4577 270)
			(unlocked yes)
			(layer "B.Fab")
			(hide yes)
			(effects
				(font
					(size 1.27 1.016)
					(thickness 0.1524)
				)
				(justify mirror)
			)
		)
		(duplicate_pad_numbers_are_jumpers no)
		(fp_line
			(start -0.508 0)
			(end 0.508 0)
			(stroke
				(width 0.2032)
				(type default)
			)
			(layer "B.SilkS")
		)
		(fp_rect
			(start 0.5842 1.3335)
			(end -0.5842 -1.3335)
			(stroke
				(width 0)
				(type default)
			)
			(fill no)
			(layer "B.CrtYd")
		)
		(fp_rect
			(start 0.5842 1.3335)
			(end -0.5842 -1.3335)
			(stroke
				(width 0)
				(type default)
			)
			(fill no)
			(layer "B.Fab")
		)
		(pad "1" smd custom
			(at 0 -0.762 90)
			(size 0.2159 0.2159)
			(layers "B.Cu" "B.Mask" "B.Paste")
			(net "BMC_SELF_HW_D_RST")
			(options
				(clearance outline)
				(anchor circle)
			)
			(primitives
				(gr_poly
					(pts
						(arc
							(start -0.3302 0.4318)
							(mid -0.402042 0.402042)
							(end -0.4318 0.3302)
						)
						(arc
							(start -0.4318 -0.3302)
							(mid -0.402042 -0.402042)
							(end -0.3302 -0.4318)
						)
						(arc
							(start 0.3302 -0.4318)
							(mid 0.402042 -0.402042)
							(end 0.4318 -0.3302)
						)
						(arc
							(start 0.4318 0.3302)
							(mid 0.402042 0.402042)
							(end 0.3302 0.4318)
						)
					)
					(width 0)
					(fill yes)
				)
			)
		)
		(pad "2" smd custom
			(at 0 0.762 90)
			(size 0.2159 0.2159)
			(layers "B.Cu" "B.Mask" "B.Paste")
			(net "BMC_TPM_HW_C_RST")
			(options
				(clearance outline)
				(anchor circle)
			)
			(primitives
				(gr_poly
					(pts
						(arc
							(start -0.3302 0.4318)
							(mid -0.402042 0.402042)
							(end -0.4318 0.3302)
						)
						(arc
							(start -0.4318 -0.3302)
							(mid -0.402042 -0.402042)
							(end -0.3302 -0.4318)
						)
						(arc
							(start 0.3302 -0.4318)
							(mid 0.402042 -0.402042)
							(end 0.4318 -0.3302)
						)
						(arc
							(start 0.4318 0.3302)
							(mid 0.402042 0.402042)
							(end 0.3302 0.4318)
						)
					)
					(width 0)
					(fill yes)
				)
			)
		)
	)
	(footprint ""
		(layer "B.Cu")
		(at 419.481 -73.1901 180)
		(property "Reference" "R1R5"
			(at 0 0 0)
			(layer "B.SilkS")
			(hide yes)
			(effects
				(font
					(size 1.27 1.27)
				)
				(justify mirror)
			)
		)
		(property "Value" ""
			(at 0 0 0)
			(layer "B.Fab")
			(effects
				(font
					(size 1.27 1.27)
				)
				(justify mirror)
			)
		)
		(duplicate_pad_numbers_are_jumpers no)
		(fp_poly
			(pts
				(xy 0.2794 -0.1016) (xy -0.2794 -0.1016) (xy -0.2794 0.9906) (xy 0.2794 0.9906)
			)
			(stroke
				(width 0)
				(type default)
			)
			(fill no)
			(layer "B.CrtYd")
		)
		(fp_line
			(start 0.2794 0.9906)
			(end -0.2794 0.9906)
			(stroke
				(width 0.1)
				(type default)
			)
			(layer "B.Fab")
		)
		(fp_line
			(start 0.2794 -0.1016)
			(end 0.2794 0.9906)
			(stroke
				(width 0.1)
				(type default)
			)
			(layer "B.Fab")
		)
		(fp_line
			(start -0.2794 0.9906)
			(end -0.2794 -0.1016)
			(stroke
				(width 0.1)
				(type default)
			)
			(layer "B.Fab")
		)
		(fp_line
			(start -0.2794 -0.1016)
			(end 0.2794 -0.1016)
			(stroke
				(width 0.1)
				(type default)
			)
			(layer "B.Fab")
		)
		(pad "1" smd rect
			(at 0 0)
			(size 0.508 0.508)
			(layers "B.Cu" "B.Mask" "B.Paste")
			(net "P3V3_STBY")
		)
		(pad "2" smd rect
			(at 0 0.889)
			(size 0.508 0.508)
			(layers "B.Cu" "B.Mask" "B.Paste")
			(net "FM_FAST_PROCHOT_THROTTLE_DLY_BU")
		)
		(zone
			(layer "B.Cu")
			(hatch none 0.5)
			(connect_pads
				(clearance 0)
			)
			(min_thickness 0.25)
			(keepout
				(tracks not_allowed)
				(vias allowed)
				(pads allowed)
				(copperpour not_allowed)
				(footprints allowed)
			)
			(placement
				(enabled no)
				(sheetname "")
			)
			(fill
				(thermal_gap 0.5)
				(thermal_bridge_width 0.5)
				(island_removal_mode 0)
			)
			(polygon
				(pts
					(xy 419.227 -73.8251) (xy 419.735 -73.8251) (xy 419.735 -73.4441) (xy 419.227 -73.4441)
				)
			)
		)
		(zone
			(layer "B.Cu")
			(hatch none 0.5)
			(connect_pads
				(clearance 0)
			)
			(min_thickness 0.25)
			(keepout
				(tracks allowed)
				(vias not_allowed)
				(pads allowed)
				(copperpour not_allowed)
				(footprints allowed)
			)
			(placement
				(enabled no)
				(sheetname "")
			)
			(fill
				(thermal_gap 0.5)
				(thermal_bridge_width 0.5)
				(island_removal_mode 0)
			)
			(polygon
				(pts
					(xy 419.227 -73.4441) (xy 419.735 -73.4441) (xy 419.735 -73.8251) (xy 419.227 -73.8251)
				)
			)
		)
	)
	(footprint ""
		(layer "B.Cu")
		(at 155.293568 -144.977612 90)
		(property "Reference" "C7L6"
			(at 0 0 90)
			(layer "B.SilkS")
			(hide yes)
			(effects
				(font
					(size 1.27 1.27)
				)
				(justify mirror)
			)
		)
		(property "Value" ""
			(at 0 0 90)
			(layer "B.Fab")
			(effects
				(font
					(size 1.27 1.27)
				)
				(justify mirror)
			)
		)
		(duplicate_pad_numbers_are_jumpers no)
		(fp_rect
			(start 0.4953 1.6002)
			(end -0.4953 -0.2032)
			(stroke
				(width 0)
				(type default)
			)
			(fill no)
			(layer "B.CrtYd")
		)
		(fp_line
			(start 0.4953 -0.2032)
			(end -0.4953 -0.2032)
			(stroke
				(width 0.1)
				(type default)
			)
			(layer "B.Fab")
		)
		(fp_line
			(start -0.4953 -0.2032)
			(end -0.4953 1.6002)
			(stroke
				(width 0.1)
				(type default)
			)
			(layer "B.Fab")
		)
		(fp_line
			(start 0.4953 1.6002)
			(end 0.4953 -0.2032)
			(stroke
				(width 0.1)
				(type default)
			)
			(layer "B.Fab")
		)
		(fp_line
			(start -0.4953 1.6002)
			(end 0.4953 1.6002)
			(stroke
				(width 0.1)
				(type default)
			)
			(layer "B.Fab")
		)
		(pad "1" smd rect
			(at 0 0 270)
			(size 0.762 0.889)
			(layers "B.Cu" "B.Mask" "B.Paste")
			(net "PVPP_KLM")
		)
		(pad "2" smd rect
			(at 0 1.397 270)
			(size 0.762 0.889)
			(layers "B.Cu" "B.Mask" "B.Paste")
			(net "GND")
		)
		(zone
			(layer "B.Cu")
			(hatch none 0.5)
			(connect_pads
				(clearance 0)
			)
			(min_thickness 0.25)
			(keepout
				(tracks not_allowed)
				(vias allowed)
				(pads allowed)
				(copperpour not_allowed)
				(footprints allowed)
			)
			(placement
				(enabled no)
				(sheetname "")
			)
			(fill
				(thermal_gap 0.5)
				(thermal_bridge_width 0.5)
				(island_removal_mode 0)
			)
			(polygon
				(pts
					(xy 156.246068 -145.358612) (xy 155.738068 -145.358612) (xy 155.738068 -144.596612) (xy 156.246068 -144.596612)
				)
			)
		)
	)
)
